(kicad_pcb
	(version 20260206)
	(generator "pcbnew")
	(generator_version "10.0")
	(general
		(thickness 1.6)
		(legacy_teardrops no)
	)
	(paper "A4")
	(title_block
		(title "fcb — 12433-1M.1206WZS1330.brd")
		(comment 1 "Open Vault / Knox (Wiwynn) / footprints 443-447 of 495")
	)
	(layers
		(0 "F.Cu" signal "TOP")
		(4 "In1.Cu" signal "L2GND")
		(6 "In2.Cu" signal "L3VCC")
		(2 "B.Cu" signal "BOTTOM")
		(9 "F.Adhes" user "F.Adhesive")
		(11 "B.Adhes" user "B.Adhesive")
		(13 "F.Paste" user "Package Geometry/Pastemask Top")
		(15 "B.Paste" user "Package Geometry/Pastemask Bottom")
		(5 "F.SilkS" user "Ref Des/Silkscreen Top")
		(7 "B.SilkS" user "Ref Des/Silkscreen Bottom")
		(1 "F.Mask" user "Board Geometry/Soldermask Top")
		(3 "B.Mask" user "Board Geometry/Soldermask Bottom")
		(17 "Dwgs.User" user "User.Drawings")
		(19 "Cmts.User" user "User.Comments")
		(21 "Eco1.User" user "User.Eco1")
		(23 "Eco2.User" user "User.Eco2")
		(25 "Edge.Cuts" user "Board Geometry/Outline")
		(27 "Margin" user)
		(31 "F.CrtYd" user "Package Geometry/Place Bound Top")
		(29 "B.CrtYd" user "Package Geometry/Place Bound Bottom")
		(35 "F.Fab" user "Ref Des/Assembly Top")
		(33 "B.Fab" user "Ref Des/Assembly Bottom")
	)
	(footprint ""
		(layer "F.Cu")
		(at 7.3152 -78.5114)
		(property "Reference" "Q4"
			(at 0 0 0)
			(layer "F.SilkS")
			(hide yes)
			(effects
				(font
					(size 1.27 1.27)
				)
			)
		)
		(property "Value" "PMBS3904-1-GP"
			(at 0 -9.0932 0)
			(unlocked yes)
			(layer "F.Fab")
			(hide yes)
			(effects
				(font
					(size 1.016 1.016)
					(thickness 0.1524)
				)
			)
		)
		(property "Device Type" "SOT-23-10H44"
			(at 0 -10.6172 0)
			(unlocked yes)
			(layer "F.Fab")
			(hide yes)
			(effects
				(font
					(size 1.016 1.016)
					(thickness 0.1524)
				)
			)
		)
		(duplicate_pad_numbers_are_jumpers no)
		(fp_line
			(start -1.7526 1.8796)
			(end -1.7526 0.9906)
			(stroke
				(width 0.3302)
				(type default)
			)
			(layer "F.SilkS")
		)
		(fp_line
			(start -1.651 -1.778)
			(end -1.651 1.778)
			(stroke
				(width 0.1524)
				(type default)
			)
			(layer "F.SilkS")
		)
		(fp_line
			(start -1.651 1.778)
			(end 1.651 1.778)
			(stroke
				(width 0.1524)
				(type default)
			)
			(layer "F.SilkS")
		)
		(fp_line
			(start -1.279398 2.152142)
			(end -0.9906 1.86309)
			(stroke
				(width 0.0127)
				(type default)
			)
			(layer "F.SilkS")
		)
		(fp_line
			(start -1.279144 2.15265)
			(end -0.701294 2.15265)
			(stroke
				(width 0.0127)
				(type default)
			)
			(layer "F.SilkS")
		)
		(fp_line
			(start -1.260856 2.1336)
			(end -0.720344 2.1336)
			(stroke
				(width 0.0127)
				(type default)
			)
			(layer "F.SilkS")
		)
		(fp_line
			(start -1.251458 2.124202)
			(end -0.729996 2.124202)
			(stroke
				(width 0.0127)
				(type default)
			)
			(layer "F.SilkS")
		)
		(fp_line
			(start -1.241806 2.11455)
			(end -0.739394 2.11455)
			(stroke
				(width 0.0127)
				(type default)
			)
			(layer "F.SilkS")
		)
		(fp_line
			(start -1.232408 2.105152)
			(end -0.749046 2.105152)
			(stroke
				(width 0.0127)
				(type default)
			)
			(layer "F.SilkS")
		)
		(fp_line
			(start -1.222756 2.0955)
			(end -0.758444 2.0955)
			(stroke
				(width 0.0127)
				(type default)
			)
			(layer "F.SilkS")
		)
		(fp_line
			(start -1.213358 2.086102)
			(end -0.768096 2.086102)
			(stroke
				(width 0.0127)
				(type default)
			)
			(layer "F.SilkS")
		)
		(fp_line
			(start -1.203706 2.07645)
			(end -0.777494 2.07645)
			(stroke
				(width 0.0127)
				(type default)
			)
			(layer "F.SilkS")
		)
		(fp_line
			(start -1.194308 2.067052)
			(end -0.787146 2.067052)
			(stroke
				(width 0.0127)
				(type default)
			)
			(layer "F.SilkS")
		)
		(fp_line
			(start -1.184656 2.0574)
			(end -0.796544 2.0574)
			(stroke
				(width 0.0127)
				(type default)
			)
			(layer "F.SilkS")
		)
		(fp_line
			(start -1.175258 2.048002)
			(end -0.806196 2.048002)
			(stroke
				(width 0.0127)
				(type default)
			)
			(layer "F.SilkS")
		)
		(fp_line
			(start -1.165606 2.03835)
			(end -0.815594 2.03835)
			(stroke
				(width 0.0127)
				(type default)
			)
			(layer "F.SilkS")
		)
		(fp_line
			(start -1.156208 2.028952)
			(end -0.825246 2.028952)
			(stroke
				(width 0.0127)
				(type default)
			)
			(layer "F.SilkS")
		)
		(fp_line
			(start -1.146556 2.0193)
			(end -0.834644 2.0193)
			(stroke
				(width 0.0127)
				(type default)
			)
			(layer "F.SilkS")
		)
		(fp_line
			(start -1.137158 2.009902)
			(end -0.844296 2.009902)
			(stroke
				(width 0.0127)
				(type default)
			)
			(layer "F.SilkS")
		)
		(fp_line
			(start -1.127506 2.00025)
			(end -0.853694 2.00025)
			(stroke
				(width 0.0127)
				(type default)
			)
			(layer "F.SilkS")
		)
		(fp_line
			(start -1.118108 1.990852)
			(end -0.863346 1.990852)
			(stroke
				(width 0.0127)
				(type default)
			)
			(layer "F.SilkS")
		)
		(fp_line
			(start -1.108456 1.9812)
			(end -0.872744 1.9812)
			(stroke
				(width 0.0127)
				(type default)
			)
			(layer "F.SilkS")
		)
		(fp_line
			(start -1.099058 1.971802)
			(end -0.882396 1.971802)
			(stroke
				(width 0.0127)
				(type default)
			)
			(layer "F.SilkS")
		)
		(fp_line
			(start -1.089406 1.96215)
			(end -0.891794 1.96215)
			(stroke
				(width 0.0127)
				(type default)
			)
			(layer "F.SilkS")
		)
		(fp_line
			(start -1.080008 1.952752)
			(end -0.901446 1.952752)
			(stroke
				(width 0.0127)
				(type default)
			)
			(layer "F.SilkS")
		)
		(fp_line
			(start -1.070356 1.9431)
			(end -0.910844 1.9431)
			(stroke
				(width 0.0127)
				(type default)
			)
			(layer "F.SilkS")
		)
		(fp_line
			(start -1.060958 1.933702)
			(end -0.920496 1.933702)
			(stroke
				(width 0.0127)
				(type default)
			)
			(layer "F.SilkS")
		)
		(fp_line
			(start -1.051306 1.92405)
			(end -0.929894 1.92405)
			(stroke
				(width 0.0127)
				(type default)
			)
			(layer "F.SilkS")
		)
		(fp_line
			(start -1.041908 1.914652)
			(end -0.939546 1.914652)
			(stroke
				(width 0.0127)
				(type default)
			)
			(layer "F.SilkS")
		)
		(fp_line
			(start -1.032256 1.905)
			(end -0.948944 1.905)
			(stroke
				(width 0.0127)
				(type default)
			)
			(layer "F.SilkS")
		)
		(fp_line
			(start -1.022858 1.895602)
			(end -0.958596 1.895602)
			(stroke
				(width 0.0127)
				(type default)
			)
			(layer "F.SilkS")
		)
		(fp_line
			(start -1.013206 1.88595)
			(end -0.967994 1.88595)
			(stroke
				(width 0.0127)
				(type default)
			)
			(layer "F.SilkS")
		)
		(fp_line
			(start -1.003808 1.876552)
			(end -0.977646 1.876552)
			(stroke
				(width 0.0127)
				(type default)
			)
			(layer "F.SilkS")
		)
		(fp_line
			(start -0.994156 1.8669)
			(end -0.987044 1.8669)
			(stroke
				(width 0.0127)
				(type default)
			)
			(layer "F.SilkS")
		)
		(fp_line
			(start -0.9906 1.86309)
			(end -0.701294 2.15265)
			(stroke
				(width 0.0127)
				(type default)
			)
			(layer "F.SilkS")
		)
		(fp_line
			(start -0.719074 2.145538)
			(end -1.265936 2.14122)
			(stroke
				(width 0.0127)
				(type default)
			)
			(layer "F.SilkS")
		)
		(fp_line
			(start -0.71628 2.15265)
			(end -1.26492 2.15265)
			(stroke
				(width 0.0127)
				(type default)
			)
			(layer "F.SilkS")
		)
		(fp_line
			(start -0.635 1.8796)
			(end -1.7526 1.8796)
			(stroke
				(width 0.3302)
				(type default)
			)
			(layer "F.SilkS")
		)
		(fp_line
			(start 1.651 -1.778)
			(end -1.651 -1.778)
			(stroke
				(width 0.1524)
				(type default)
			)
			(layer "F.SilkS")
		)
		(fp_line
			(start 1.651 1.778)
			(end 1.651 -1.778)
			(stroke
				(width 0.1524)
				(type default)
			)
			(layer "F.SilkS")
		)
		(fp_poly
			(pts
				(xy -1.285748 2.159) (xy -1.285748 1.8796) (xy -1.778 1.8796) (xy -1.778 -1.8796) (xy 1.778 -1.8796)
				(xy 1.778 1.8796) (xy -0.694944 1.8796) (xy -0.694944 2.159)
			)
			(stroke
				(width 0)
				(type default)
			)
			(fill no)
			(layer "F.CrtYd")
		)
		(fp_poly
			(pts
				(xy -1.285748 2.159) (xy -1.285748 1.8796) (xy -1.778 1.8796) (xy -1.778 -1.8796) (xy 1.778 -1.8796)
				(xy 1.778 1.8796) (xy -0.694944 1.8796) (xy -0.694944 2.159)
			)
			(stroke
				(width 0)
				(type default)
			)
			(fill no)
			(layer "F.Fab")
		)
		(pad "1" smd rect
			(at -0.98425 0.9525)
			(size 0.762 1.143)
			(layers "F.Cu" "F.Mask" "F.Paste")
			(net "LED_DR_LED4_B")
		)
		(pad "2" smd rect
			(at 0.98425 0.9525)
			(size 0.762 1.143)
			(layers "F.Cu" "F.Mask" "F.Paste")
			(net "GND")
		)
		(pad "3" smd rect
			(at 0 -0.9525)
			(size 0.762 1.143)
			(layers "F.Cu" "F.Mask" "F.Paste")
			(net "LED_DR_LED4_BLUE")
		)
	)
	(footprint ""
		(layer "F.Cu")
		(at 27.559 -217.780616)
		(property "Reference" "U7"
			(at 0 0 0)
			(layer "F.SilkS")
			(hide yes)
			(effects
				(font
					(size 1.27 1.27)
				)
			)
		)
		(property "Value" "TSLV07APWR-GP"
			(at -7.112 -6.0579 0)
			(unlocked yes)
			(layer "F.Fab")
			(hide yes)
			(effects
				(font
					(size 1.016 1.016)
					(thickness 0.1524)
				)
			)
		)
		(property "Device Type" "TSOIC14H48"
			(at -7.112 -7.5819 0)
			(unlocked yes)
			(layer "F.Fab")
			(hide yes)
			(effects
				(font
					(size 1.016 1.016)
					(thickness 0.1524)
				)
			)
		)
		(duplicate_pad_numbers_are_jumpers no)
		(fp_line
			(start -2.9718 -1.778)
			(end 2.1336 -1.778)
			(stroke
				(width 0.1524)
				(type default)
			)
			(layer "F.SilkS")
		)
		(fp_line
			(start -2.9718 1.778)
			(end -2.9718 -1.778)
			(stroke
				(width 0.1524)
				(type default)
			)
			(layer "F.SilkS")
		)
		(fp_line
			(start -2.9337 -0.4699)
			(end -2.9083 -0.4699)
			(stroke
				(width 0.1524)
				(type default)
			)
			(layer "F.SilkS")
		)
		(fp_line
			(start -2.9083 -0.4699)
			(end -2.4384 0)
			(stroke
				(width 0.1524)
				(type default)
			)
			(layer "F.SilkS")
		)
		(fp_line
			(start -2.8956 0.4572)
			(end -2.921 0.4572)
			(stroke
				(width 0.1524)
				(type default)
			)
			(layer "F.SilkS")
		)
		(fp_line
			(start -2.794 3.8227)
			(end -2.794 1.7018)
			(stroke
				(width 0.508)
				(type default)
			)
			(layer "F.SilkS")
		)
		(fp_line
			(start -2.4384 0)
			(end -2.8956 0.4572)
			(stroke
				(width 0.1524)
				(type default)
			)
			(layer "F.SilkS")
		)
		(fp_line
			(start 2.1336 -1.778)
			(end 2.1336 1.778)
			(stroke
				(width 0.1524)
				(type default)
			)
			(layer "F.SilkS")
		)
		(fp_line
			(start 2.1336 1.778)
			(end -2.9718 1.778)
			(stroke
				(width 0.1524)
				(type default)
			)
			(layer "F.SilkS")
		)
		(fp_poly
			(pts
				(xy -2.1336 -1.7653) (xy 2.1336 -1.7653) (xy 2.1336 1.778) (xy -2.1336 1.778)
			)
			(stroke
				(width 0)
				(type default)
			)
			(fill yes)
			(layer "F.SilkS")
		)
		(fp_rect
			(start -2.5019 3.2004)
			(end 2.5019 -3.2004)
			(stroke
				(width 0)
				(type default)
			)
			(fill no)
			(layer "F.CrtYd")
		)
		(fp_poly
			(pts
				(xy -3.048 4.0894) (xy -3.048 -2.5781) (xy -2.5019 -2.5781) (xy -2.5019 3.2004) (xy 2.5019 3.2004)
				(xy 2.5019 -3.2004) (xy -2.5019 -3.2004) (xy -2.5019 -2.5908) (xy -3.048 -2.5908) (xy -3.048 -4.0894)
				(xy 3.048 -4.0894) (xy 3.048 4.0894)
			)
			(stroke
				(width 0)
				(type default)
			)
			(fill no)
			(layer "F.CrtYd")
		)
		(fp_rect
			(start -3.048 4.0894)
			(end 3.048 -4.0894)
			(stroke
				(width 0)
				(type default)
			)
			(fill no)
			(layer "F.Fab")
		)
		(pad "1" smd rect
			(at -1.94945 2.8194)
			(size 0.3556 1.524)
			(layers "F.Cu" "F.Mask" "F.Paste")
			(net "PWM_BUFFER_IN_FAN5_FAN6")
		)
		(pad "2" smd rect
			(at -1.30048 2.8194)
			(size 0.3556 1.524)
			(layers "F.Cu" "F.Mask" "F.Paste")
			(net "PWM_OUT_FAN6")
		)
		(pad "3" smd rect
			(at -0.65024 2.8194)
			(size 0.3556 1.524)
			(layers "F.Cu" "F.Mask" "F.Paste")
			(net "PWM_BUFFER_IN_FAN5_FAN6")
		)
		(pad "4" smd rect
			(at 0 2.8194)
			(size 0.3556 1.524)
			(layers "F.Cu" "F.Mask" "F.Paste")
			(net "PWM_OUT_FAN5")
		)
		(pad "5" smd rect
			(at 0.65024 2.8194)
			(size 0.3556 1.524)
			(layers "F.Cu" "F.Mask" "F.Paste")
			(net "PWM_BUFFER_IN_FAN3_FAN4")
		)
		(pad "6" smd rect
			(at 1.30048 2.8194)
			(size 0.3556 1.524)
			(layers "F.Cu" "F.Mask" "F.Paste")
			(net "PWM_OUT_FAN4")
		)
		(pad "7" smd rect
			(at 1.94945 2.8194)
			(size 0.3556 1.524)
			(layers "F.Cu" "F.Mask" "F.Paste")
			(net "GND")
		)
		(pad "8" smd rect
			(at 1.94945 -2.8194)
			(size 0.3556 1.524)
			(layers "F.Cu" "F.Mask" "F.Paste")
			(net "PWM_OUT_FAN3")
		)
		(pad "9" smd rect
			(at 1.30048 -2.8194)
			(size 0.3556 1.524)
			(layers "F.Cu" "F.Mask" "F.Paste")
			(net "PWM_BUFFER_IN_FAN3_FAN4")
		)
		(pad "10" smd rect
			(at 0.65024 -2.8194)
			(size 0.3556 1.524)
			(layers "F.Cu" "F.Mask" "F.Paste")
			(net "PWM_OUT_FAN2")
		)
		(pad "11" smd rect
			(at 0 -2.8194)
			(size 0.3556 1.524)
			(layers "F.Cu" "F.Mask" "F.Paste")
			(net "PWM_BUFFER_IN_FAN1_FAN2")
		)
		(pad "12" smd rect
			(at -0.65024 -2.8194)
			(size 0.3556 1.524)
			(layers "F.Cu" "F.Mask" "F.Paste")
			(net "PWM_OUT_FAN1")
		)
		(pad "13" smd rect
			(at -1.30048 -2.8194)
			(size 0.3556 1.524)
			(layers "F.Cu" "F.Mask" "F.Paste")
			(net "PWM_BUFFER_IN_FAN1_FAN2")
		)
		(pad "14" smd rect
			(at -1.94945 -2.8194)
			(size 0.3556 1.524)
			(layers "F.Cu" "F.Mask" "F.Paste")
			(net "P3V3")
		)
	)
	(footprint ""
		(layer "F.Cu")
		(at 19.2278 -182.1942)
		(property "Reference" "C36"
			(at 0 0 0)
			(layer "F.SilkS")
			(hide yes)
			(effects
				(font
					(size 1.27 1.27)
				)
			)
		)
		(property "Value" "SCD1U16V2KX-3GP"
			(at 1.1811 -2.7051 0)
			(unlocked yes)
			(layer "F.Fab")
			(hide yes)
			(effects
				(font
					(size 1.016 1.016)
					(thickness 0.1524)
				)
			)
		)
		(property "Device Type" "C402H22"
			(at 1.1811 -4.2291 0)
			(unlocked yes)
			(layer "F.Fab")
			(hide yes)
			(effects
				(font
					(size 1.016 1.016)
					(thickness 0.1524)
				)
			)
		)
		(duplicate_pad_numbers_are_jumpers no)
		(fp_rect
			(start -0.4318 0.9525)
			(end 0.4318 -0.9525)
			(stroke
				(width 0)
				(type default)
			)
			(fill no)
			(layer "F.CrtYd")
		)
		(fp_rect
			(start -0.4318 0.9525)
			(end 0.4318 -0.9525)
			(stroke
				(width 0)
				(type default)
			)
			(fill no)
			(layer "F.Fab")
		)
		(pad "1" smd custom
			(at 0 -0.4445)
			(size 0.1524 0.1524)
			(layers "F.Cu" "F.Mask" "F.Paste")
			(net "FAN_TACH7")
			(options
				(clearance outline)
				(anchor circle)
			)
			(primitives
				(gr_poly
					(pts
						(arc
							(start 0.3048 -0.2032)
							(mid 0.275042 -0.275042)
							(end 0.2032 -0.3048)
						)
						(arc
							(start -0.2032 -0.3048)
							(mid -0.275042 -0.275042)
							(end -0.3048 -0.2032)
						)
						(arc
							(start -0.3048 0.2032)
							(mid -0.275042 0.275042)
							(end -0.2032 0.3048)
						)
						(arc
							(start 0.2032 0.3048)
							(mid 0.275042 0.275042)
							(end 0.3048 0.2032)
						)
					)
					(width 0)
					(fill yes)
				)
			)
		)
		(pad "2" smd custom
			(at 0 0.4445)
			(size 0.1524 0.1524)
			(layers "F.Cu" "F.Mask" "F.Paste")
			(net "GND")
			(options
				(clearance outline)
				(anchor circle)
			)
			(primitives
				(gr_poly
					(pts
						(arc
							(start 0.3048 -0.2032)
							(mid 0.275042 -0.275042)
							(end 0.2032 -0.3048)
						)
						(arc
							(start -0.2032 -0.3048)
							(mid -0.275042 -0.275042)
							(end -0.3048 -0.2032)
						)
						(arc
							(start -0.3048 0.2032)
							(mid -0.275042 0.275042)
							(end -0.2032 0.3048)
						)
						(arc
							(start 0.2032 0.3048)
							(mid 0.275042 0.275042)
							(end 0.3048 0.2032)
						)
					)
					(width 0)
					(fill yes)
				)
			)
		)
	)
	(footprint ""
		(layer "F.Cu")
		(at 31.9024 -91.8972 90)
		(property "Reference" "D16"
			(at 0 0 90)
			(layer "F.SilkS")
			(hide yes)
			(effects
				(font
					(size 1.27 1.27)
				)
			)
		)
		(property "Value" "MBRS340T3G-GP"
			(at 0 -10.6172 90)
			(unlocked yes)
			(layer "F.Fab")
			(hide yes)
			(effects
				(font
					(size 1.016 1.016)
					(thickness 0.1524)
				)
			)
		)
		(property "Device Type" "D8059AKH101"
			(at 0 -12.1412 90)
			(unlocked yes)
			(layer "F.Fab")
			(hide yes)
			(effects
				(font
					(size 1.016 1.016)
					(thickness 0.1524)
				)
			)
		)
		(duplicate_pad_numbers_are_jumpers no)
		(fp_line
			(start 3.175 -5.1054)
			(end 3.175 5.1054)
			(stroke
				(width 0.1524)
				(type default)
			)
			(layer "F.SilkS")
		)
		(fp_line
			(start -3.175 -5.1054)
			(end 3.175 -5.1054)
			(stroke
				(width 0.1524)
				(type default)
			)
			(layer "F.SilkS")
		)
		(fp_line
			(start 3.175 5.1054)
			(end -3.175 5.1054)
			(stroke
				(width 0.1524)
				(type default)
			)
			(layer "F.SilkS")
		)
		(fp_line
			(start -3.175 5.1054)
			(end -3.175 -5.1054)
			(stroke
				(width 0.1524)
				(type default)
			)
			(layer "F.SilkS")
		)
		(fp_line
			(start 3.175 5.2832)
			(end -3.175 5.2832)
			(stroke
				(width 0.508)
				(type default)
			)
			(layer "F.SilkS")
		)
		(fp_rect
			(start -3.429 5.1816)
			(end 3.429 -5.1816)
			(stroke
				(width 0)
				(type default)
			)
			(fill no)
			(layer "F.CrtYd")
		)
		(fp_poly
			(pts
				(xy -3.429 -5.1816) (xy 3.429 -5.1816) (xy 3.429 5.1816) (xy -3.429 5.1816)
			)
			(stroke
				(width 0)
				(type default)
			)
			(fill no)
			(layer "F.Fab")
		)
		(pad "A" smd rect
			(at 0 -3.77571 90)
			(size 3.2512 2.159)
			(layers "F.Cu" "F.Mask" "F.Paste")
			(net "GND")
		)
		(pad "K" smd rect
			(at 0 3.77571 90)
			(size 3.2512 2.159)
			(layers "F.Cu" "F.Mask" "F.Paste")
			(net "P12VL")
		)
	)
	(footprint ""
		(layer "F.Cu")
		(at 36.83 -240.665 180)
		(property "Reference" "R148"
			(at 0 0 180)
			(layer "F.SilkS")
			(hide yes)
			(effects
				(font
					(size 1.27 1.27)
				)
			)
		)
		(property "Value" "330R2J-3-GP"
			(at 0.064008 -3.993896 180)
			(unlocked yes)
			(layer "F.Fab")
			(hide yes)
			(effects
				(font
					(size 1.016 1.016)
					(thickness 0.1524)
				)
			)
		)
		(property "Device Type" "R402H16"
			(at 0.064008 -5.517896 180)
			(unlocked yes)
			(layer "F.Fab")
			(hide yes)
			(effects
				(font
					(size 1.016 1.016)
					(thickness 0.1524)
				)
			)
		)
		(duplicate_pad_numbers_are_jumpers no)
		(fp_line
			(start 0.508 -0.9398)
			(end -0.508 -0.9398)
			(stroke
				(width 0.1524)
				(type default)
			)
			(layer "F.SilkS")
		)
		(fp_line
			(start -0.508 -0.9398)
			(end -0.508 0.9398)
			(stroke
				(width 0.1524)
				(type default)
			)
			(layer "F.SilkS")
		)
		(fp_rect
			(start -0.508 0.9398)
			(end 0.508 -0.9398)
			(stroke
				(width 0)
				(type default)
			)
			(fill no)
			(layer "F.CrtYd")
		)
		(fp_rect
			(start -0.508 0.9398)
			(end 0.508 -0.9398)
			(stroke
				(width 0)
				(type default)
			)
			(fill no)
			(layer "F.Fab")
		)
		(pad "1" smd custom
			(at 0 -0.4445 180)
			(size 0.1397 0.1397)
			(layers "F.Cu" "F.Mask" "F.Paste")
			(net "P3V3")
			(options
				(clearance outline)
				(anchor circle)
			)
			(primitives
				(gr_poly
					(pts
						(arc
							(start -0.1778 -0.2794)
							(mid -0.249642 -0.249642)
							(end -0.2794 -0.1778)
						)
						(arc
							(start -0.2794 0.1778)
							(mid -0.249642 0.249642)
							(end -0.1778 0.2794)
						)
						(arc
							(start 0.1778 0.2794)
							(mid 0.249642 0.249642)
							(end 0.2794 0.1778)
						)
						(arc
							(start 0.2794 -0.1778)
							(mid 0.249642 -0.249642)
							(end 0.1778 -0.2794)
						)
					)
					(width 0)
					(fill yes)
				)
			)
		)
		(pad "2" smd custom
			(at 0 0.4445 180)
			(size 0.1397 0.1397)
			(layers "F.Cu" "F.Mask" "F.Paste")
			(net "LED_DR_LED0")
			(options
				(clearance outline)
				(anchor circle)
			)
			(primitives
				(gr_poly
					(pts
						(arc
							(start -0.1778 -0.2794)
							(mid -0.249642 -0.249642)
							(end -0.2794 -0.1778)
						)
						(arc
							(start -0.2794 0.1778)
							(mid -0.249642 0.249642)
							(end -0.1778 0.2794)
						)
						(arc
							(start 0.1778 0.2794)
							(mid 0.249642 0.249642)
							(end 0.2794 0.1778)
						)
						(arc
							(start 0.2794 -0.1778)
							(mid 0.249642 -0.249642)
							(end 0.1778 -0.2794)
						)
					)
					(width 0)
					(fill yes)
				)
			)
		)
	)
)
